FILE_TYPE=LIBRARY_PARTS;
primitive 'CONN36_G97614001','CONN36_G97614001_CP';
  pin
    'GND1':
      PIN_NUMBER='(A3)';
      PINUSE='GROUND';
      NO_LOAD_CHECK='Both';
      NO_IO_CHECK='Both';
      NO_ASSERT_CHECK='TRUE';
      NO_DIR_CHECK='TRUE';
      ALLOW_CONNECT='TRUE';
    'GND10':
      PIN_NUMBER='(D3)';
      PINUSE='GROUND';
      NO_LOAD_CHECK='Both';
      NO_IO_CHECK='Both';
      NO_ASSERT_CHECK='TRUE';
      NO_DIR_CHECK='TRUE';
      ALLOW_CONNECT='TRUE';
    'GND11':
      PIN_NUMBER='(D6)';
      PINUSE='GROUND';
      NO_LOAD_CHECK='Both';
      NO_IO_CHECK='Both';
      NO_ASSERT_CHECK='TRUE';
      NO_DIR_CHECK='TRUE';
      ALLOW_CONNECT='TRUE';
    'GND12':
      PIN_NUMBER='(D9)';
      PINUSE='GROUND';
      NO_LOAD_CHECK='Both';
      NO_IO_CHECK='Both';
      NO_ASSERT_CHECK='TRUE';
      NO_DIR_CHECK='TRUE';
      ALLOW_CONNECT='TRUE';
    'GND2':
      PIN_NUMBER='(A6)';
      PINUSE='GROUND';
      NO_LOAD_CHECK='Both';
      NO_IO_CHECK='Both';
      NO_ASSERT_CHECK='TRUE';
      NO_DIR_CHECK='TRUE';
      ALLOW_CONNECT='TRUE';
    'GND3':
      PIN_NUMBER='(A9)';
      PINUSE='GROUND';
      NO_LOAD_CHECK='Both';
      NO_IO_CHECK='Both';
      NO_ASSERT_CHECK='TRUE';
      NO_DIR_CHECK='TRUE';
      ALLOW_CONNECT='TRUE';
    'GND4':
      PIN_NUMBER='(B3)';
      PINUSE='GROUND';
      NO_LOAD_CHECK='Both';
      NO_IO_CHECK='Both';
      NO_ASSERT_CHECK='TRUE';
      NO_DIR_CHECK='TRUE';
      ALLOW_CONNECT='TRUE';
    'GND5':
      PIN_NUMBER='(B6)';
      PINUSE='GROUND';
      NO_LOAD_CHECK='Both';
      NO_IO_CHECK='Both';
      NO_ASSERT_CHECK='TRUE';
      NO_DIR_CHECK='TRUE';
      ALLOW_CONNECT='TRUE';
    'GND6':
      PIN_NUMBER='(B9)';
      PINUSE='GROUND';
      NO_LOAD_CHECK='Both';
      NO_IO_CHECK='Both';
      NO_ASSERT_CHECK='TRUE';
      NO_DIR_CHECK='TRUE';
      ALLOW_CONNECT='TRUE';
    'GND7':
      PIN_NUMBER='(C3)';
      PINUSE='GROUND';
      NO_LOAD_CHECK='Both';
      NO_IO_CHECK='Both';
      NO_ASSERT_CHECK='TRUE';
      NO_DIR_CHECK='TRUE';
      ALLOW_CONNECT='TRUE';
    'GND8':
      PIN_NUMBER='(C6)';
      PINUSE='GROUND';
      NO_LOAD_CHECK='Both';
      NO_IO_CHECK='Both';
      NO_ASSERT_CHECK='TRUE';
      NO_DIR_CHECK='TRUE';
      ALLOW_CONNECT='TRUE';
    'GND9':
      PIN_NUMBER='(C9)';
      PINUSE='GROUND';
      NO_LOAD_CHECK='Both';
      NO_IO_CHECK='Both';
      NO_ASSERT_CHECK='TRUE';
      NO_DIR_CHECK='TRUE';
      ALLOW_CONNECT='TRUE';
    'RXA0_DN':
      PIN_NUMBER='(B5)';
      INPUT_LOAD='(-0.01,0.01)';
      OUTPUT_LOAD='(1.0,-1.0)';
      OUTPUT_TYPE='(TS,TS)';
      BIDIRECTIONAL='TRUE';
      PIN_GROUP='1';
    'RXA0_DP':
      PIN_NUMBER='(B4)';
      INPUT_LOAD='(-0.01,0.01)';
      OUTPUT_LOAD='(1.0,-1.0)';
      OUTPUT_TYPE='(TS,TS)';
      BIDIRECTIONAL='TRUE';
      PIN_GROUP='1';
    'RXA1_DN':
      PIN_NUMBER='(A5)';
      INPUT_LOAD='(-0.01,0.01)';
      OUTPUT_LOAD='(1.0,-1.0)';
      OUTPUT_TYPE='(TS,TS)';
      BIDIRECTIONAL='TRUE';
      PIN_GROUP='1';
    'RXA1_DP':
      PIN_NUMBER='(A4)';
      INPUT_LOAD='(-0.01,0.01)';
      OUTPUT_LOAD='(1.0,-1.0)';
      OUTPUT_TYPE='(TS,TS)';
      BIDIRECTIONAL='TRUE';
      PIN_GROUP='1';
    'RXA2_DN':
      PIN_NUMBER='(B8)';
      INPUT_LOAD='(-0.01,0.01)';
      OUTPUT_LOAD='(1.0,-1.0)';
      OUTPUT_TYPE='(TS,TS)';
      BIDIRECTIONAL='TRUE';
      PIN_GROUP='1';
    'RXA2_DP':
      PIN_NUMBER='(B7)';
      INPUT_LOAD='(-0.01,0.01)';
      OUTPUT_LOAD='(1.0,-1.0)';
      OUTPUT_TYPE='(TS,TS)';
      BIDIRECTIONAL='TRUE';
      PIN_GROUP='1';
    'RXA3_DN':
      PIN_NUMBER='(A8)';
      INPUT_LOAD='(-0.01,0.01)';
      OUTPUT_LOAD='(1.0,-1.0)';
      OUTPUT_TYPE='(TS,TS)';
      BIDIRECTIONAL='TRUE';
      PIN_GROUP='1';
    'RXA3_DP':
      PIN_NUMBER='(A7)';
      INPUT_LOAD='(-0.01,0.01)';
      OUTPUT_LOAD='(1.0,-1.0)';
      OUTPUT_TYPE='(TS,TS)';
      BIDIRECTIONAL='TRUE';
      PIN_GROUP='1';
    'SIDEBAND0':
      PIN_NUMBER='(A2)';
      INPUT_LOAD='(-0.01,0.01)';
      OUTPUT_LOAD='(1.0,-1.0)';
      OUTPUT_TYPE='(TS,TS)';
      BIDIRECTIONAL='TRUE';
      PIN_GROUP='1';
    'SIDEBAND1':
      PIN_NUMBER='(B2)';
      INPUT_LOAD='(-0.01,0.01)';
      OUTPUT_LOAD='(1.0,-1.0)';
      OUTPUT_TYPE='(TS,TS)';
      BIDIRECTIONAL='TRUE';
      PIN_GROUP='1';
    'SIDEBAND2':
      PIN_NUMBER='(C2)';
      INPUT_LOAD='(-0.01,0.01)';
      OUTPUT_LOAD='(1.0,-1.0)';
      OUTPUT_TYPE='(TS,TS)';
      BIDIRECTIONAL='TRUE';
      PIN_GROUP='1';
    'SIDEBAND3':
      PIN_NUMBER='(B1)';
      INPUT_LOAD='(-0.01,0.01)';
      OUTPUT_LOAD='(1.0,-1.0)';
      OUTPUT_TYPE='(TS,TS)';
      BIDIRECTIONAL='TRUE';
      PIN_GROUP='1';
    'SIDEBAND4':
      PIN_NUMBER='(C1)';
      INPUT_LOAD='(-0.01,0.01)';
      OUTPUT_LOAD='(1.0,-1.0)';
      OUTPUT_TYPE='(TS,TS)';
      BIDIRECTIONAL='TRUE';
      PIN_GROUP='1';
    'SIDEBAND5':
      PIN_NUMBER='(D1)';
      INPUT_LOAD='(-0.01,0.01)';
      OUTPUT_LOAD='(1.0,-1.0)';
      OUTPUT_TYPE='(TS,TS)';
      BIDIRECTIONAL='TRUE';
      PIN_GROUP='1';
    'SIDEBAND6':
      PIN_NUMBER='(D2)';
      INPUT_LOAD='(-0.01,0.01)';
      OUTPUT_LOAD='(1.0,-1.0)';
      OUTPUT_TYPE='(TS,TS)';
      BIDIRECTIONAL='TRUE';
      PIN_GROUP='1';
    'SIDEBAND7':
      PIN_NUMBER='(A1)';
      INPUT_LOAD='(-0.01,0.01)';
      OUTPUT_LOAD='(1.0,-1.0)';
      OUTPUT_TYPE='(TS,TS)';
      BIDIRECTIONAL='TRUE';
      PIN_GROUP='1';
    'TXA0_DN':
      PIN_NUMBER='(D5)';
      INPUT_LOAD='(-0.01,0.01)';
      OUTPUT_LOAD='(1.0,-1.0)';
      OUTPUT_TYPE='(TS,TS)';
      BIDIRECTIONAL='TRUE';
      PIN_GROUP='1';
    'TXA0_DP':
      PIN_NUMBER='(D4)';
      INPUT_LOAD='(-0.01,0.01)';
      OUTPUT_LOAD='(1.0,-1.0)';
      OUTPUT_TYPE='(TS,TS)';
      BIDIRECTIONAL='TRUE';
      PIN_GROUP='1';
    'TXA1_DN':
      PIN_NUMBER='(C5)';
      INPUT_LOAD='(-0.01,0.01)';
      OUTPUT_LOAD='(1.0,-1.0)';
      OUTPUT_TYPE='(TS,TS)';
      BIDIRECTIONAL='TRUE';
      PIN_GROUP='1';
    'TXA1_DP':
      PIN_NUMBER='(C4)';
      INPUT_LOAD='(-0.01,0.01)';
      OUTPUT_LOAD='(1.0,-1.0)';
      OUTPUT_TYPE='(TS,TS)';
      BIDIRECTIONAL='TRUE';
      PIN_GROUP='1';
    'TXA2_DN':
      PIN_NUMBER='(D8)';
      INPUT_LOAD='(-0.01,0.01)';
      OUTPUT_LOAD='(1.0,-1.0)';
      OUTPUT_TYPE='(TS,TS)';
      BIDIRECTIONAL='TRUE';
      PIN_GROUP='1';
    'TXA2_DP':
      PIN_NUMBER='(D7)';
      INPUT_LOAD='(-0.01,0.01)';
      OUTPUT_LOAD='(1.0,-1.0)';
      OUTPUT_TYPE='(TS,TS)';
      BIDIRECTIONAL='TRUE';
      PIN_GROUP='1';
    'TXA3_DN':
      PIN_NUMBER='(C8)';
      INPUT_LOAD='(-0.01,0.01)';
      OUTPUT_LOAD='(1.0,-1.0)';
      OUTPUT_TYPE='(TS,TS)';
      BIDIRECTIONAL='TRUE';
      PIN_GROUP='1';
    'TXA3_DP':
      PIN_NUMBER='(C7)';
      INPUT_LOAD='(-0.01,0.01)';
      OUTPUT_LOAD='(1.0,-1.0)';
      OUTPUT_TYPE='(TS,TS)';
      BIDIRECTIONAL='TRUE';
      PIN_GROUP='1';
  end_pin;
  body
    PART_NAME='CONN36_G97614001';
    PHYS_DES_PREFIX='J';
  end_body;
end_primitive;

primitive 'CONN36_G97614001_BP';
  pin
    'GND1':
      PIN_NUMBER='(A3)';
      PINUSE='GROUND';
      NO_LOAD_CHECK='Both';
      NO_IO_CHECK='Both';
      NO_ASSERT_CHECK='TRUE';
      NO_DIR_CHECK='TRUE';
      ALLOW_CONNECT='TRUE';
    'GND10':
      PIN_NUMBER='(D3)';
      PINUSE='GROUND';
      NO_LOAD_CHECK='Both';
      NO_IO_CHECK='Both';
      NO_ASSERT_CHECK='TRUE';
      NO_DIR_CHECK='TRUE';
      ALLOW_CONNECT='TRUE';
    'GND11':
      PIN_NUMBER='(D6)';
      PINUSE='GROUND';
      NO_LOAD_CHECK='Both';
      NO_IO_CHECK='Both';
      NO_ASSERT_CHECK='TRUE';
      NO_DIR_CHECK='TRUE';
      ALLOW_CONNECT='TRUE';
    'GND12':
      PIN_NUMBER='(D9)';
      PINUSE='GROUND';
      NO_LOAD_CHECK='Both';
      NO_IO_CHECK='Both';
      NO_ASSERT_CHECK='TRUE';
      NO_DIR_CHECK='TRUE';
      ALLOW_CONNECT='TRUE';
    'GND2':
      PIN_NUMBER='(A6)';
      PINUSE='GROUND';
      NO_LOAD_CHECK='Both';
      NO_IO_CHECK='Both';
      NO_ASSERT_CHECK='TRUE';
      NO_DIR_CHECK='TRUE';
      ALLOW_CONNECT='TRUE';
    'GND3':
      PIN_NUMBER='(A9)';
      PINUSE='GROUND';
      NO_LOAD_CHECK='Both';
      NO_IO_CHECK='Both';
      NO_ASSERT_CHECK='TRUE';
      NO_DIR_CHECK='TRUE';
      ALLOW_CONNECT='TRUE';
    'GND4':
      PIN_NUMBER='(B3)';
      PINUSE='GROUND';
      NO_LOAD_CHECK='Both';
      NO_IO_CHECK='Both';
      NO_ASSERT_CHECK='TRUE';
      NO_DIR_CHECK='TRUE';
      ALLOW_CONNECT='TRUE';
    'GND5':
      PIN_NUMBER='(B6)';
      PINUSE='GROUND';
      NO_LOAD_CHECK='Both';
      NO_IO_CHECK='Both';
      NO_ASSERT_CHECK='TRUE';
      NO_DIR_CHECK='TRUE';
      ALLOW_CONNECT='TRUE';
    'GND6':
      PIN_NUMBER='(B9)';
      PINUSE='GROUND';
      NO_LOAD_CHECK='Both';
      NO_IO_CHECK='Both';
      NO_ASSERT_CHECK='TRUE';
      NO_DIR_CHECK='TRUE';
      ALLOW_CONNECT='TRUE';
    'GND7':
      PIN_NUMBER='(C3)';
      PINUSE='GROUND';
      NO_LOAD_CHECK='Both';
      NO_IO_CHECK='Both';
      NO_ASSERT_CHECK='TRUE';
      NO_DIR_CHECK='TRUE';
      ALLOW_CONNECT='TRUE';
    'GND8':
      PIN_NUMBER='(C6)';
      PINUSE='GROUND';
      NO_LOAD_CHECK='Both';
      NO_IO_CHECK='Both';
      NO_ASSERT_CHECK='TRUE';
      NO_DIR_CHECK='TRUE';
      ALLOW_CONNECT='TRUE';
    'GND9':
      PIN_NUMBER='(C9)';
      PINUSE='GROUND';
      NO_LOAD_CHECK='Both';
      NO_IO_CHECK='Both';
      NO_ASSERT_CHECK='TRUE';
      NO_DIR_CHECK='TRUE';
      ALLOW_CONNECT='TRUE';
    'RXA0_DN':
      PIN_NUMBER='(B5)';
      INPUT_LOAD='(-0.01,0.01)';
      OUTPUT_LOAD='(1.0,-1.0)';
      OUTPUT_TYPE='(TS,TS)';
      BIDIRECTIONAL='TRUE';
      PIN_GROUP='1';
    'RXA0_DP':
      PIN_NUMBER='(B4)';
      INPUT_LOAD='(-0.01,0.01)';
      OUTPUT_LOAD='(1.0,-1.0)';
      OUTPUT_TYPE='(TS,TS)';
      BIDIRECTIONAL='TRUE';
      PIN_GROUP='1';
    'RXA1_DN':
      PIN_NUMBER='(A5)';
      INPUT_LOAD='(-0.01,0.01)';
      OUTPUT_LOAD='(1.0,-1.0)';
      OUTPUT_TYPE='(TS,TS)';
      BIDIRECTIONAL='TRUE';
      PIN_GROUP='1';
    'RXA1_DP':
      PIN_NUMBER='(A4)';
      INPUT_LOAD='(-0.01,0.01)';
      OUTPUT_LOAD='(1.0,-1.0)';
      OUTPUT_TYPE='(TS,TS)';
      BIDIRECTIONAL='TRUE';
      PIN_GROUP='1';
    'RXA2_DN':
      PIN_NUMBER='(B8)';
      INPUT_LOAD='(-0.01,0.01)';
      OUTPUT_LOAD='(1.0,-1.0)';
      OUTPUT_TYPE='(TS,TS)';
      BIDIRECTIONAL='TRUE';
      PIN_GROUP='1';
    'RXA2_DP':
      PIN_NUMBER='(B7)';
      INPUT_LOAD='(-0.01,0.01)';
      OUTPUT_LOAD='(1.0,-1.0)';
      OUTPUT_TYPE='(TS,TS)';
      BIDIRECTIONAL='TRUE';
      PIN_GROUP='1';
    'RXA3_DN':
      PIN_NUMBER='(A8)';
      INPUT_LOAD='(-0.01,0.01)';
      OUTPUT_LOAD='(1.0,-1.0)';
      OUTPUT_TYPE='(TS,TS)';
      BIDIRECTIONAL='TRUE';
      PIN_GROUP='1';
    'RXA3_DP':
      PIN_NUMBER='(A7)';
      INPUT_LOAD='(-0.01,0.01)';
      OUTPUT_LOAD='(1.0,-1.0)';
      OUTPUT_TYPE='(TS,TS)';
      BIDIRECTIONAL='TRUE';
      PIN_GROUP='1';
    'SIDEBAND0':
      PIN_NUMBER='(A1)';
      INPUT_LOAD='(-0.01,0.01)';
      OUTPUT_LOAD='(1.0,-1.0)';
      OUTPUT_TYPE='(TS,TS)';
      BIDIRECTIONAL='TRUE';
      PIN_GROUP='1';
    'SIDEBAND1':
      PIN_NUMBER='(B1)';
      INPUT_LOAD='(-0.01,0.01)';
      OUTPUT_LOAD='(1.0,-1.0)';
      OUTPUT_TYPE='(TS,TS)';
      BIDIRECTIONAL='TRUE';
      PIN_GROUP='1';
    'SIDEBAND2':
      PIN_NUMBER='(C1)';
      INPUT_LOAD='(-0.01,0.01)';
      OUTPUT_LOAD='(1.0,-1.0)';
      OUTPUT_TYPE='(TS,TS)';
      BIDIRECTIONAL='TRUE';
      PIN_GROUP='1';
    'SIDEBAND3':
      PIN_NUMBER='(B2)';
      INPUT_LOAD='(-0.01,0.01)';
      OUTPUT_LOAD='(1.0,-1.0)';
      OUTPUT_TYPE='(TS,TS)';
      BIDIRECTIONAL='TRUE';
      PIN_GROUP='1';
    'SIDEBAND4':
      PIN_NUMBER='(C2)';
      INPUT_LOAD='(-0.01,0.01)';
      OUTPUT_LOAD='(1.0,-1.0)';
      OUTPUT_TYPE='(TS,TS)';
      BIDIRECTIONAL='TRUE';
      PIN_GROUP='1';
    'SIDEBAND5':
      PIN_NUMBER='(D2)';
      INPUT_LOAD='(-0.01,0.01)';
      OUTPUT_LOAD='(1.0,-1.0)';
      OUTPUT_TYPE='(TS,TS)';
      BIDIRECTIONAL='TRUE';
      PIN_GROUP='1';
    'SIDEBAND6':
      PIN_NUMBER='(D1)';
      INPUT_LOAD='(-0.01,0.01)';
      OUTPUT_LOAD='(1.0,-1.0)';
      OUTPUT_TYPE='(TS,TS)';
      BIDIRECTIONAL='TRUE';
      PIN_GROUP='1';
    'SIDEBAND7':
      PIN_NUMBER='(A2)';
      INPUT_LOAD='(-0.01,0.01)';
      OUTPUT_LOAD='(1.0,-1.0)';
      OUTPUT_TYPE='(TS,TS)';
      BIDIRECTIONAL='TRUE';
      PIN_GROUP='1';
    'TXA0_DN':
      PIN_NUMBER='(D5)';
      INPUT_LOAD='(-0.01,0.01)';
      OUTPUT_LOAD='(1.0,-1.0)';
      OUTPUT_TYPE='(TS,TS)';
      BIDIRECTIONAL='TRUE';
      PIN_GROUP='1';
    'TXA0_DP':
      PIN_NUMBER='(D4)';
      INPUT_LOAD='(-0.01,0.01)';
      OUTPUT_LOAD='(1.0,-1.0)';
      OUTPUT_TYPE='(TS,TS)';
      BIDIRECTIONAL='TRUE';
      PIN_GROUP='1';
    'TXA1_DN':
      PIN_NUMBER='(C5)';
      INPUT_LOAD='(-0.01,0.01)';
      OUTPUT_LOAD='(1.0,-1.0)';
      OUTPUT_TYPE='(TS,TS)';
      BIDIRECTIONAL='TRUE';
      PIN_GROUP='1';
    'TXA1_DP':
      PIN_NUMBER='(C4)';
      INPUT_LOAD='(-0.01,0.01)';
      OUTPUT_LOAD='(1.0,-1.0)';
      OUTPUT_TYPE='(TS,TS)';
      BIDIRECTIONAL='TRUE';
      PIN_GROUP='1';
    'TXA2_DN':
      PIN_NUMBER='(D8)';
      INPUT_LOAD='(-0.01,0.01)';
      OUTPUT_LOAD='(1.0,-1.0)';
      OUTPUT_TYPE='(TS,TS)';
      BIDIRECTIONAL='TRUE';
      PIN_GROUP='1';
    'TXA2_DP':
      PIN_NUMBER='(D7)';
      INPUT_LOAD='(-0.01,0.01)';
      OUTPUT_LOAD='(1.0,-1.0)';
      OUTPUT_TYPE='(TS,TS)';
      BIDIRECTIONAL='TRUE';
      PIN_GROUP='1';
    'TXA3_DN':
      PIN_NUMBER='(C8)';
      INPUT_LOAD='(-0.01,0.01)';
      OUTPUT_LOAD='(1.0,-1.0)';
      OUTPUT_TYPE='(TS,TS)';
      BIDIRECTIONAL='TRUE';
      PIN_GROUP='1';
    'TXA3_DP':
      PIN_NUMBER='(C7)';
      INPUT_LOAD='(-0.01,0.01)';
      OUTPUT_LOAD='(1.0,-1.0)';
      OUTPUT_TYPE='(TS,TS)';
      BIDIRECTIONAL='TRUE';
      PIN_GROUP='1';
  end_pin;
  body
    PART_NAME='CONN36_G97614001';
    PHYS_DES_PREFIX='J';
  end_body;
end_primitive;

END.
